# T6G (Grand Teton) — schematic netlist excerpt (pin names and nets, part order shuffled) for the footprints in the layout excerpt that follows; sources: Cadence DE-HDL packaged netlist, KiCad conversion of 04192023_DAF0TMB3IC0_F0TG_MB_C_brd_V02_OCP.brd

R6296  Q_RES  0 5% CHIP  pkg 0402LF  page 178 : A = USB_HUB2_MRP_I2C_SLV_CFG1 ; B = USB_HUB2_TI_OVERCUR4_MRP_I2C_SLV_CFG1
R209  Q_RES  0 5% CHIP  pkg 0402LF  page 81 : A = PWRGD_PVDDCR_CPU0_P1 ; B = FM_PWRGD_PVDDCR_CPU0_P1

(kicad_pcb
	(version 20260206)
	(generator "pcbnew")
	(generator_version "10.0")
	(general
		(thickness 1.6)
		(legacy_teardrops no)
	)
	(paper "A4")
	(title_block
		(title "04192023_DAF0TMB3IC0_F0TG_MB_C_brd_V02_OCP.brd")
		(comment 1 "Grand Teton / footprints 4314-4315 of 8354")
	)
	(layers
		(0 "F.Cu" signal "TOP")
		(4 "In1.Cu" signal "GND")
		(6 "In2.Cu" signal "IN1")
		(8 "In3.Cu" signal "GND1")
		(10 "In4.Cu" signal "IN2")
		(12 "In5.Cu" signal "GND2")
		(14 "In6.Cu" signal "IN3")
		(16 "In7.Cu" signal "GND3")
		(18 "In8.Cu" signal "VCC")
		(20 "In9.Cu" signal "VCC1")
		(22 "In10.Cu" signal "GND4")
		(24 "In11.Cu" signal "IN4")
		(26 "In12.Cu" signal "GND5")
		(28 "In13.Cu" signal "IN5")
		(30 "In14.Cu" signal "GND6")
		(32 "In15.Cu" signal "IN6")
		(34 "In16.Cu" signal "GND7")
		(2 "B.Cu" signal "BOTTOM")
		(9 "F.Adhes" user "F.Adhesive")
		(11 "B.Adhes" user "B.Adhesive")
		(13 "F.Paste" user "Package Geometry/Pastemask Top")
		(15 "B.Paste" user "Package Geometry/Pastemask Bottom")
		(5 "F.SilkS" user "Ref Des/Silkscreen Top")
		(7 "B.SilkS" user "Ref Des/Silkscreen Bottom")
		(1 "F.Mask" user "Board Geometry/Soldermask Top")
		(3 "B.Mask" user "Board Geometry/Soldermask Bottom")
		(17 "Dwgs.User" user "User.Drawings")
		(19 "Cmts.User" user "User.Comments")
		(21 "Eco1.User" user "User.Eco1")
		(23 "Eco2.User" user "User.Eco2")
		(25 "Edge.Cuts" user "Board Geometry/Outline")
		(27 "Margin" user)
		(31 "F.CrtYd" user "Package Geometry/Place Bound Top")
		(29 "B.CrtYd" user "Package Geometry/Place Bound Bottom")
		(35 "F.Fab" user "Ref Des/Assembly Top")
		(33 "B.Fab" user "Ref Des/Assembly Bottom")
	)
	(footprint ""
		(layer "F.Cu")
		(at 115.010946 -53.49748 180)
		(property "Reference" "R6296"
			(at 0 0 180)
			(layer "F.SilkS")
			(hide yes)
			(effects
				(font
					(size 1.27 1.27)
				)
			)
		)
		(property "Value" ""
			(at 0 0 180)
			(layer "F.Fab")
			(effects
				(font
					(size 1.27 1.27)
				)
			)
		)
		(duplicate_pad_numbers_are_jumpers no)
		(fp_line
			(start 0.7874 0.4064)
			(end -0.7874 0.4064)
			(stroke
				(width 0.1524)
				(type default)
			)
			(layer "F.SilkS")
		)
		(fp_line
			(start 0.7874 -0.4064)
			(end 0.7874 0.4064)
			(stroke
				(width 0.1524)
				(type default)
			)
			(layer "F.SilkS")
		)
		(fp_line
			(start -0.7874 0.4064)
			(end -0.7874 -0.4064)
			(stroke
				(width 0.1524)
				(type default)
			)
			(layer "F.SilkS")
		)
		(fp_line
			(start -0.7874 -0.4064)
			(end 0.7874 -0.4064)
			(stroke
				(width 0.1524)
				(type default)
			)
			(layer "F.SilkS")
		)
		(fp_line
			(start 0.67945 0.3048)
			(end 0.120396 0.3048)
			(stroke
				(width 0.1)
				(type default)
			)
			(layer "F.Fab")
		)
		(fp_line
			(start 0.67945 -0.3048)
			(end 0.67945 0.3048)
			(stroke
				(width 0.1)
				(type default)
			)
			(layer "F.Fab")
		)
		(fp_line
			(start 0.12065 -0.2794)
			(end 0.12065 -0.3048)
			(stroke
				(width 0.1)
				(type default)
			)
			(layer "F.Fab")
		)
		(fp_line
			(start 0.12065 -0.3048)
			(end 0.67945 -0.3048)
			(stroke
				(width 0.1)
				(type default)
			)
			(layer "F.Fab")
		)
		(fp_line
			(start 0.120396 0.3048)
			(end 0.120396 0.2794)
			(stroke
				(width 0.1)
				(type default)
			)
			(layer "F.Fab")
		)
		(fp_line
			(start 0.120396 0.2794)
			(end -0.12065 0.2794)
			(stroke
				(width 0.1)
				(type default)
			)
			(layer "F.Fab")
		)
		(fp_line
			(start -0.12065 0.3048)
			(end -0.67945 0.3048)
			(stroke
				(width 0.1)
				(type default)
			)
			(layer "F.Fab")
		)
		(fp_line
			(start -0.12065 0.2794)
			(end -0.12065 0.3048)
			(stroke
				(width 0.1)
				(type default)
			)
			(layer "F.Fab")
		)
		(fp_line
			(start -0.12065 -0.2794)
			(end 0.12065 -0.2794)
			(stroke
				(width 0.1)
				(type default)
			)
			(layer "F.Fab")
		)
		(fp_line
			(start -0.12065 -0.305054)
			(end -0.12065 -0.2794)
			(stroke
				(width 0.1)
				(type default)
			)
			(layer "F.Fab")
		)
		(fp_line
			(start -0.67945 0.3048)
			(end -0.67945 -0.305054)
			(stroke
				(width 0.1)
				(type default)
			)
			(layer "F.Fab")
		)
		(fp_line
			(start -0.67945 -0.305054)
			(end -0.12065 -0.305054)
			(stroke
				(width 0.1)
				(type default)
			)
			(layer "F.Fab")
		)
		(pad "1" smd circle
			(at -0.40005 0 180)
			(size 0 0)
			(layers "F.Cu" "F.Mask" "F.Paste")
			(net "USB_HUB2_MRP_I2C_SLV_CFG1")
		)
		(pad "2" smd circle
			(at 0.40005 0 180)
			(size 0 0)
			(layers "F.Cu" "F.Mask" "F.Paste")
			(net "USB_HUB2_TI_OVERCUR4_MRP_I2C_SLV_CFG1")
		)
	)
	(footprint ""
		(layer "F.Cu")
		(at 200.939908 -108.545376 180)
		(property "Reference" "R209"
			(at 0 0 180)
			(layer "F.SilkS")
			(hide yes)
			(effects
				(font
					(size 1.27 1.27)
				)
			)
		)
		(property "Value" ""
			(at 0 0 180)
			(layer "F.Fab")
			(effects
				(font
					(size 1.27 1.27)
				)
			)
		)
		(duplicate_pad_numbers_are_jumpers no)
		(fp_line
			(start 0.7874 0.4064)
			(end -0.7874 0.4064)
			(stroke
				(width 0.1524)
				(type default)
			)
			(layer "F.SilkS")
		)
		(fp_line
			(start 0.7874 -0.4064)
			(end 0.7874 0.4064)
			(stroke
				(width 0.1524)
				(type default)
			)
			(layer "F.SilkS")
		)
		(fp_line
			(start -0.7874 0.4064)
			(end -0.7874 -0.4064)
			(stroke
				(width 0.1524)
				(type default)
			)
			(layer "F.SilkS")
		)
		(fp_line
			(start -0.7874 -0.4064)
			(end 0.7874 -0.4064)
			(stroke
				(width 0.1524)
				(type default)
			)
			(layer "F.SilkS")
		)
		(fp_line
			(start 0.67945 0.3048)
			(end 0.120396 0.3048)
			(stroke
				(width 0.1)
				(type default)
			)
			(layer "F.Fab")
		)
		(fp_line
			(start 0.67945 -0.3048)
			(end 0.67945 0.3048)
			(stroke
				(width 0.1)
				(type default)
			)
			(layer "F.Fab")
		)
		(fp_line
			(start 0.12065 -0.2794)
			(end 0.12065 -0.3048)
			(stroke
				(width 0.1)
				(type default)
			)
			(layer "F.Fab")
		)
		(fp_line
			(start 0.12065 -0.3048)
			(end 0.67945 -0.3048)
			(stroke
				(width 0.1)
				(type default)
			)
			(layer "F.Fab")
		)
		(fp_line
			(start 0.120396 0.3048)
			(end 0.120396 0.2794)
			(stroke
				(width 0.1)
				(type default)
			)
			(layer "F.Fab")
		)
		(fp_line
			(start 0.120396 0.2794)
			(end -0.12065 0.2794)
			(stroke
				(width 0.1)
				(type default)
			)
			(layer "F.Fab")
		)
		(fp_line
			(start -0.12065 0.3048)
			(end -0.67945 0.3048)
			(stroke
				(width 0.1)
				(type default)
			)
			(layer "F.Fab")
		)
		(fp_line
			(start -0.12065 0.2794)
			(end -0.12065 0.3048)
			(stroke
				(width 0.1)
				(type default)
			)
			(layer "F.Fab")
		)
		(fp_line
			(start -0.12065 -0.2794)
			(end 0.12065 -0.2794)
			(stroke
				(width 0.1)
				(type default)
			)
			(layer "F.Fab")
		)
		(fp_line
			(start -0.12065 -0.305054)
			(end -0.12065 -0.2794)
			(stroke
				(width 0.1)
				(type default)
			)
			(layer "F.Fab")
		)
		(fp_line
			(start -0.67945 0.3048)
			(end -0.67945 -0.305054)
			(stroke
				(width 0.1)
				(type default)
			)
			(layer "F.Fab")
		)
		(fp_line
			(start -0.67945 -0.305054)
			(end -0.12065 -0.305054)
			(stroke
				(width 0.1)
				(type default)
			)
			(layer "F.Fab")
		)
		(pad "1" smd circle
			(at -0.40005 0 180)
			(size 0 0)
			(layers "F.Cu" "F.Mask" "F.Paste")
			(net "PWRGD_PVDDCR_CPU0_P1")
		)
		(pad "2" smd circle
			(at 0.40005 0 180)
			(size 0 0)
			(layers "F.Cu" "F.Mask" "F.Paste")
			(net "FM_PWRGD_PVDDCR_CPU0_P1")
		)
	)
)
